(kicad_pcb
	(version 20260206)
	(generator "pcbnew")
	(generator_version "10.0")
	(general
		(thickness 1.6)
		(legacy_teardrops no)
	)
	(paper "A4")
	(title_block
		(title "v1-chassis-manager — T6M_CM_d_v01_1031_1645.brd")
		(comment 1 "Open CloudServer (Microsoft) / footprints 551-559 of 2512")
	)
	(layers
		(0 "F.Cu" signal "TOP")
		(4 "In1.Cu" signal "GND1")
		(6 "In2.Cu" signal "IN1")
		(8 "In3.Cu" signal "VCC1")
		(10 "In4.Cu" signal "VCC2")
		(12 "In5.Cu" signal "GND2")
		(14 "In6.Cu" signal "IN2")
		(16 "In7.Cu" signal "IN3")
		(18 "In8.Cu" signal "GND3")
		(2 "B.Cu" signal "BOTTOM")
		(9 "F.Adhes" user "F.Adhesive")
		(11 "B.Adhes" user "B.Adhesive")
		(13 "F.Paste" user "Package Geometry/Pastemask Top")
		(15 "B.Paste" user "Package Geometry/Pastemask Bottom")
		(5 "F.SilkS" user "Ref Des/Silkscreen Top")
		(7 "B.SilkS" user "Ref Des/Silkscreen Bottom")
		(1 "F.Mask" user "Board Geometry/Soldermask Top")
		(3 "B.Mask" user "Board Geometry/Soldermask Bottom")
		(17 "Dwgs.User" user "User.Drawings")
		(19 "Cmts.User" user "User.Comments")
		(21 "Eco1.User" user "User.Eco1")
		(23 "Eco2.User" user "User.Eco2")
		(25 "Edge.Cuts" user "Board Geometry/Outline")
		(27 "Margin" user)
		(31 "F.CrtYd" user "Package Geometry/Place Bound Top")
		(29 "B.CrtYd" user "Package Geometry/Place Bound Bottom")
		(35 "F.Fab" user "Ref Des/Assembly Top")
		(33 "B.Fab" user "Ref Des/Assembly Bottom")
	)
	(footprint ""
		(layer "F.Cu")
		(at 134.85876 -108.370624 90)
		(property "Reference" "R188"
			(at -6.585204 0.586486 90)
			(unlocked yes)
			(layer "F.SilkS")
			(effects
				(font
					(size 0.7874 0.5842)
					(thickness 0.1524)
				)
				(justify left)
			)
		)
		(property "Value" ""
			(at 0 0 90)
			(layer "F.Fab")
			(effects
				(font
					(size 1.27 1.27)
				)
			)
		)
		(duplicate_pad_numbers_are_jumpers no)
		(fp_line
			(start 0.7874 -0.4064)
			(end 0.7874 0.4064)
			(stroke
				(width 0.1524)
				(type default)
			)
			(layer "F.SilkS")
		)
		(fp_line
			(start -0.7874 -0.4064)
			(end 0.7874 -0.4064)
			(stroke
				(width 0.1524)
				(type default)
			)
			(layer "F.SilkS")
		)
		(fp_line
			(start 0.7874 0.4064)
			(end -0.7874 0.4064)
			(stroke
				(width 0.1524)
				(type default)
			)
			(layer "F.SilkS")
		)
		(fp_line
			(start -0.7874 0.4064)
			(end -0.7874 -0.4064)
			(stroke
				(width 0.1524)
				(type default)
			)
			(layer "F.SilkS")
		)
		(fp_poly
			(pts
				(xy -0.508 0.2794) (xy -0.508 0.2286) (xy -0.635 0.2286) (xy -0.635 -0.254) (xy -0.5334 -0.254)
				(xy -0.5334 -0.2794) (xy 0.5334 -0.2794) (xy 0.5334 -0.254) (xy 0.635 -0.254) (xy 0.635 0.254) (xy 0.5334 0.254)
				(xy 0.5334 0.2794)
			)
			(stroke
				(width 0)
				(type default)
			)
			(fill no)
			(layer "F.CrtYd")
		)
		(pad "1" smd rect
			(at 0.40005 0 90)
			(size 0.4572 0.508)
			(layers "F.Cu" "F.Mask" "F.Paste")
			(net "CLP_ITP_EN_NODE1")
		)
		(pad "2" smd rect
			(at -0.40005 0 90)
			(size 0.4572 0.508)
			(layers "F.Cu" "F.Mask" "F.Paste")
			(net "CLK_33M_PORT80")
		)
	)
	(footprint ""
		(layer "F.Cu")
		(at 27.772868 -104.628696 -90)
		(property "Reference" "C819"
			(at 0.684276 1.029462 90)
			(unlocked yes)
			(layer "F.SilkS")
			(effects
				(font
					(size 0.7874 0.5842)
					(thickness 0.1524)
				)
				(justify left)
			)
		)
		(property "Value" ""
			(at 0 0 270)
			(layer "F.Fab")
			(effects
				(font
					(size 1.27 1.27)
				)
			)
		)
		(duplicate_pad_numbers_are_jumpers no)
		(fp_line
			(start -0.7874 0.4064)
			(end -0.7874 -0.4064)
			(stroke
				(width 0.1524)
				(type default)
			)
			(layer "F.SilkS")
		)
		(fp_line
			(start 0.7874 0.4064)
			(end -0.7874 0.4064)
			(stroke
				(width 0.1524)
				(type default)
			)
			(layer "F.SilkS")
		)
		(fp_line
			(start 0 0.381)
			(end 0 -0.381)
			(stroke
				(width 0.1524)
				(type default)
			)
			(layer "F.SilkS")
		)
		(fp_line
			(start -0.7874 -0.4064)
			(end 0.7874 -0.4064)
			(stroke
				(width 0.1524)
				(type default)
			)
			(layer "F.SilkS")
		)
		(fp_line
			(start 0.7874 -0.4064)
			(end 0.7874 0.4064)
			(stroke
				(width 0.1524)
				(type default)
			)
			(layer "F.SilkS")
		)
		(fp_poly
			(pts
				(xy -0.5334 0.254) (xy -0.635 0.254) (xy -0.635 0.2286) (xy -0.635 -0.254) (xy -0.5334 -0.254) (xy -0.5334 -0.2794)
				(xy 0.5334 -0.2794) (xy 0.5334 -0.254) (xy 0.635 -0.254) (xy 0.635 0.254) (xy 0.5334 0.254) (xy 0.5334 0.2794)
				(xy -0.508 0.2794) (xy -0.5334 0.2794)
			)
			(stroke
				(width 0)
				(type default)
			)
			(fill no)
			(layer "F.CrtYd")
		)
		(pad "1" smd rect
			(at 0.40005 0 270)
			(size 0.4572 0.508)
			(layers "F.Cu" "F.Mask" "F.Paste")
			(net "FM_CPLD_NODE1_P1V5_SUS_EN")
		)
		(pad "2" smd rect
			(at -0.40005 0 270)
			(size 0.4572 0.508)
			(layers "F.Cu" "F.Mask" "F.Paste")
			(net "GND")
		)
	)
	(footprint ""
		(layer "F.Cu")
		(at 136.12876 -108.370624 90)
		(property "Reference" "R14"
			(at -6.585204 0.466852 90)
			(unlocked yes)
			(layer "F.SilkS")
			(effects
				(font
					(size 0.7874 0.5842)
					(thickness 0.1524)
				)
				(justify left)
			)
		)
		(property "Value" ""
			(at 0 0 90)
			(layer "F.Fab")
			(effects
				(font
					(size 1.27 1.27)
				)
			)
		)
		(duplicate_pad_numbers_are_jumpers no)
		(fp_line
			(start 0.7874 -0.4064)
			(end 0.7874 0.4064)
			(stroke
				(width 0.1524)
				(type default)
			)
			(layer "F.SilkS")
		)
		(fp_line
			(start -0.7874 -0.4064)
			(end 0.7874 -0.4064)
			(stroke
				(width 0.1524)
				(type default)
			)
			(layer "F.SilkS")
		)
		(fp_line
			(start 0.7874 0.4064)
			(end -0.7874 0.4064)
			(stroke
				(width 0.1524)
				(type default)
			)
			(layer "F.SilkS")
		)
		(fp_line
			(start -0.7874 0.4064)
			(end -0.7874 -0.4064)
			(stroke
				(width 0.1524)
				(type default)
			)
			(layer "F.SilkS")
		)
		(fp_poly
			(pts
				(xy -0.508 0.2794) (xy -0.508 0.2286) (xy -0.635 0.2286) (xy -0.635 -0.254) (xy -0.5334 -0.254)
				(xy -0.5334 -0.2794) (xy 0.5334 -0.2794) (xy 0.5334 -0.254) (xy 0.635 -0.254) (xy 0.635 0.254) (xy 0.5334 0.254)
				(xy 0.5334 0.2794)
			)
			(stroke
				(width 0)
				(type default)
			)
			(fill no)
			(layer "F.CrtYd")
		)
		(pad "1" smd rect
			(at 0.40005 0 90)
			(size 0.4572 0.508)
			(layers "F.Cu" "F.Mask" "F.Paste")
			(net "CLK_FSLB_NODE1")
		)
		(pad "2" smd rect
			(at -0.40005 0 90)
			(size 0.4572 0.508)
			(layers "F.Cu" "F.Mask" "F.Paste")
			(net "P3V3_CLK_NODE1")
		)
	)
	(footprint ""
		(layer "F.Cu")
		(at 79.963518 -87.979504)
		(property "Reference" "R48"
			(at -1.195578 18.989294 0)
			(unlocked yes)
			(layer "F.SilkS")
			(effects
				(font
					(size 0.7874 0.5842)
					(thickness 0.1524)
				)
				(justify left)
			)
		)
		(property "Value" ""
			(at 0 0 0)
			(layer "F.Fab")
			(effects
				(font
					(size 1.27 1.27)
				)
			)
		)
		(duplicate_pad_numbers_are_jumpers no)
		(fp_line
			(start -0.7874 -0.4064)
			(end 0.7874 -0.4064)
			(stroke
				(width 0.1524)
				(type default)
			)
			(layer "F.SilkS")
		)
		(fp_line
			(start -0.7874 0.4064)
			(end -0.7874 -0.4064)
			(stroke
				(width 0.1524)
				(type default)
			)
			(layer "F.SilkS")
		)
		(fp_line
			(start 0.7874 -0.4064)
			(end 0.7874 0.4064)
			(stroke
				(width 0.1524)
				(type default)
			)
			(layer "F.SilkS")
		)
		(fp_line
			(start 0.7874 0.4064)
			(end -0.7874 0.4064)
			(stroke
				(width 0.1524)
				(type default)
			)
			(layer "F.SilkS")
		)
		(fp_poly
			(pts
				(xy -0.508 0.2794) (xy -0.508 0.2286) (xy -0.635 0.2286) (xy -0.635 -0.254) (xy -0.5334 -0.254)
				(xy -0.5334 -0.2794) (xy 0.5334 -0.2794) (xy 0.5334 -0.254) (xy 0.635 -0.254) (xy 0.635 0.254) (xy 0.5334 0.254)
				(xy 0.5334 0.2794)
			)
			(stroke
				(width 0)
				(type default)
			)
			(fill no)
			(layer "F.CrtYd")
		)
		(pad "1" smd rect
			(at 0.40005 0)
			(size 0.4572 0.508)
			(layers "F.Cu" "F.Mask" "F.Paste")
			(net "P3V3_NODE1")
		)
		(pad "2" smd rect
			(at -0.40005 0)
			(size 0.4572 0.508)
			(layers "F.Cu" "F.Mask" "F.Paste")
			(net "SPI_CPU_NODE1_WP_R_L")
		)
	)
	(footprint ""
		(layer "F.Cu")
		(at 86.458552 -145.07083 90)
		(property "Reference" "R1234"
			(at -1.63068 2.29235 90)
			(unlocked yes)
			(layer "F.SilkS")
			(effects
				(font
					(size 0.7874 0.5842)
					(thickness 0.1524)
				)
				(justify left)
			)
		)
		(property "Value" ""
			(at 0 0 90)
			(layer "F.Fab")
			(effects
				(font
					(size 1.27 1.27)
				)
			)
		)
		(duplicate_pad_numbers_are_jumpers no)
		(fp_line
			(start 0.7874 -0.4064)
			(end 0.7874 0.4064)
			(stroke
				(width 0.1524)
				(type default)
			)
			(layer "F.SilkS")
		)
		(fp_line
			(start -0.7874 -0.4064)
			(end 0.7874 -0.4064)
			(stroke
				(width 0.1524)
				(type default)
			)
			(layer "F.SilkS")
		)
		(fp_line
			(start 0.7874 0.4064)
			(end -0.7874 0.4064)
			(stroke
				(width 0.1524)
				(type default)
			)
			(layer "F.SilkS")
		)
		(fp_line
			(start -0.7874 0.4064)
			(end -0.7874 -0.4064)
			(stroke
				(width 0.1524)
				(type default)
			)
			(layer "F.SilkS")
		)
		(fp_poly
			(pts
				(xy -0.508 0.2794) (xy -0.508 0.2286) (xy -0.635 0.2286) (xy -0.635 -0.254) (xy -0.5334 -0.254)
				(xy -0.5334 -0.2794) (xy 0.5334 -0.2794) (xy 0.5334 -0.254) (xy 0.635 -0.254) (xy 0.635 0.254) (xy 0.5334 0.254)
				(xy 0.5334 0.2794)
			)
			(stroke
				(width 0)
				(type default)
			)
			(fill no)
			(layer "F.CrtYd")
		)
		(pad "1" smd rect
			(at 0.40005 0 90)
			(size 0.4572 0.508)
			(layers "F.Cu" "F.Mask" "F.Paste")
			(net "GND")
		)
		(pad "2" smd rect
			(at -0.40005 0 90)
			(size 0.4572 0.508)
			(layers "F.Cu" "F.Mask" "F.Paste")
			(net "FM_CPLD_NODE1_P1V26_BMC_EN")
		)
	)
	(footprint ""
		(layer "F.Cu")
		(at 12.98702 -121.979182)
		(property "Reference" "PC55"
			(at -5.525008 -0.243332 0)
			(unlocked yes)
			(layer "F.SilkS")
			(effects
				(font
					(size 0.7874 0.5842)
					(thickness 0.1524)
				)
				(justify left)
			)
		)
		(property "Value" ""
			(at 0 0 0)
			(layer "F.Fab")
			(effects
				(font
					(size 1.27 1.27)
				)
			)
		)
		(duplicate_pad_numbers_are_jumpers no)
		(fp_line
			(start -2.2098 -0.9398)
			(end 2.2098 -0.9398)
			(stroke
				(width 0.1524)
				(type default)
			)
			(layer "F.SilkS")
		)
		(fp_line
			(start -2.2098 0.9398)
			(end -2.2098 -0.9398)
			(stroke
				(width 0.1524)
				(type default)
			)
			(layer "F.SilkS")
		)
		(fp_line
			(start 0 -0.9398)
			(end 0 0.9398)
			(stroke
				(width 0.1524)
				(type default)
			)
			(layer "F.SilkS")
		)
		(fp_line
			(start 2.2098 -0.9398)
			(end 2.2098 0.9398)
			(stroke
				(width 0.1524)
				(type default)
			)
			(layer "F.SilkS")
		)
		(fp_line
			(start 2.2098 0.9398)
			(end -2.2098 0.9398)
			(stroke
				(width 0.1524)
				(type default)
			)
			(layer "F.SilkS")
		)
		(fp_poly
			(pts
				(xy -1.6764 0.889) (xy -1.6764 0.7874) (xy -2.0574 0.7874) (xy -2.0574 -0.7874) (xy -1.6764 -0.7874)
				(xy -1.6764 -0.9398) (xy 1.6764 -0.9398) (xy 1.6764 -0.7874) (xy 2.0574 -0.7874) (xy 2.0574 0.7874)
				(xy 1.6764 0.7874) (xy 1.6764 0.9398) (xy -1.6764 0.9398)
			)
			(stroke
				(width 0)
				(type default)
			)
			(fill no)
			(layer "F.CrtYd")
		)
		(fp_line
			(start -1.700022 -0.899922)
			(end 1.700022 -0.899922)
			(stroke
				(width 0.1)
				(type default)
			)
			(layer "F.Fab")
		)
		(fp_line
			(start -1.700022 0.899922)
			(end -1.700022 -0.899922)
			(stroke
				(width 0.1)
				(type default)
			)
			(layer "F.Fab")
		)
		(fp_line
			(start 1.700022 -0.899922)
			(end 1.700022 0.899922)
			(stroke
				(width 0.1)
				(type default)
			)
			(layer "F.Fab")
		)
		(fp_line
			(start 1.700022 0.899922)
			(end -1.700022 0.899922)
			(stroke
				(width 0.1)
				(type default)
			)
			(layer "F.Fab")
		)
		(pad "1" smd rect
			(at 1.4732 0)
			(size 1.1684 1.5748)
			(layers "F.Cu" "F.Mask" "F.Paste")
			(net "SW_P1V05_NODE1_VIN_FLT")
		)
		(pad "2" smd rect
			(at -1.4732 0)
			(size 1.1684 1.5748)
			(layers "F.Cu" "F.Mask" "F.Paste")
			(net "GND")
		)
	)
	(footprint ""
		(layer "F.Cu")
		(at 77.03185 -151.842724)
		(property "Reference" "PC2"
			(at -3.893312 -0.161036 0)
			(unlocked yes)
			(layer "F.SilkS")
			(effects
				(font
					(size 0.7874 0.5842)
					(thickness 0.1524)
				)
				(justify left)
			)
		)
		(property "Value" ""
			(at 0 0 0)
			(layer "F.Fab")
			(effects
				(font
					(size 1.27 1.27)
				)
			)
		)
		(duplicate_pad_numbers_are_jumpers no)
		(fp_line
			(start -0.7874 -0.4064)
			(end 0.7874 -0.4064)
			(stroke
				(width 0.1524)
				(type default)
			)
			(layer "F.SilkS")
		)
		(fp_line
			(start -0.7874 0.4064)
			(end -0.7874 -0.4064)
			(stroke
				(width 0.1524)
				(type default)
			)
			(layer "F.SilkS")
		)
		(fp_line
			(start 0 0.381)
			(end 0 -0.381)
			(stroke
				(width 0.1524)
				(type default)
			)
			(layer "F.SilkS")
		)
		(fp_line
			(start 0.7874 -0.4064)
			(end 0.7874 0.4064)
			(stroke
				(width 0.1524)
				(type default)
			)
			(layer "F.SilkS")
		)
		(fp_line
			(start 0.7874 0.4064)
			(end -0.7874 0.4064)
			(stroke
				(width 0.1524)
				(type default)
			)
			(layer "F.SilkS")
		)
		(fp_poly
			(pts
				(xy -0.5334 0.254) (xy -0.635 0.254) (xy -0.635 0.2286) (xy -0.635 -0.254) (xy -0.5334 -0.254) (xy -0.5334 -0.2794)
				(xy 0.5334 -0.2794) (xy 0.5334 -0.254) (xy 0.635 -0.254) (xy 0.635 0.254) (xy 0.5334 0.254) (xy 0.5334 0.2794)
				(xy -0.508 0.2794) (xy -0.5334 0.2794)
			)
			(stroke
				(width 0)
				(type default)
			)
			(fill no)
			(layer "F.CrtYd")
		)
		(pad "1" smd rect
			(at 0.40005 0)
			(size 0.4572 0.508)
			(layers "F.Cu" "F.Mask" "F.Paste")
			(net "P12V_AUX")
		)
		(pad "2" smd rect
			(at -0.40005 0)
			(size 0.4572 0.508)
			(layers "F.Cu" "F.Mask" "F.Paste")
			(net "GND")
		)
	)
	(footprint ""
		(layer "F.Cu")
		(at 13.041884 -124.093224)
		(property "Reference" "PC56"
			(at -5.58419 0.842772 0)
			(unlocked yes)
			(layer "F.SilkS")
			(effects
				(font
					(size 0.7874 0.5842)
					(thickness 0.1524)
				)
				(justify left)
			)
		)
		(property "Value" ""
			(at 0 0 0)
			(layer "F.Fab")
			(effects
				(font
					(size 1.27 1.27)
				)
			)
		)
		(duplicate_pad_numbers_are_jumpers no)
		(fp_line
			(start -2.2098 -0.9398)
			(end 2.2098 -0.9398)
			(stroke
				(width 0.1524)
				(type default)
			)
			(layer "F.SilkS")
		)
		(fp_line
			(start -2.2098 0.9398)
			(end -2.2098 -0.9398)
			(stroke
				(width 0.1524)
				(type default)
			)
			(layer "F.SilkS")
		)
		(fp_line
			(start 0 -0.9398)
			(end 0 0.9398)
			(stroke
				(width 0.1524)
				(type default)
			)
			(layer "F.SilkS")
		)
		(fp_line
			(start 2.2098 -0.9398)
			(end 2.2098 0.9398)
			(stroke
				(width 0.1524)
				(type default)
			)
			(layer "F.SilkS")
		)
		(fp_line
			(start 2.2098 0.9398)
			(end -2.2098 0.9398)
			(stroke
				(width 0.1524)
				(type default)
			)
			(layer "F.SilkS")
		)
		(fp_poly
			(pts
				(xy -1.6764 0.889) (xy -1.6764 0.7874) (xy -2.0574 0.7874) (xy -2.0574 -0.7874) (xy -1.6764 -0.7874)
				(xy -1.6764 -0.9398) (xy 1.6764 -0.9398) (xy 1.6764 -0.7874) (xy 2.0574 -0.7874) (xy 2.0574 0.7874)
				(xy 1.6764 0.7874) (xy 1.6764 0.9398) (xy -1.6764 0.9398)
			)
			(stroke
				(width 0)
				(type default)
			)
			(fill no)
			(layer "F.CrtYd")
		)
		(fp_line
			(start -1.700022 -0.899922)
			(end 1.700022 -0.899922)
			(stroke
				(width 0.1)
				(type default)
			)
			(layer "F.Fab")
		)
		(fp_line
			(start -1.700022 0.899922)
			(end -1.700022 -0.899922)
			(stroke
				(width 0.1)
				(type default)
			)
			(layer "F.Fab")
		)
		(fp_line
			(start 1.700022 -0.899922)
			(end 1.700022 0.899922)
			(stroke
				(width 0.1)
				(type default)
			)
			(layer "F.Fab")
		)
		(fp_line
			(start 1.700022 0.899922)
			(end -1.700022 0.899922)
			(stroke
				(width 0.1)
				(type default)
			)
			(layer "F.Fab")
		)
		(pad "1" smd rect
			(at 1.4732 0)
			(size 1.1684 1.5748)
			(layers "F.Cu" "F.Mask" "F.Paste")
			(net "SW_P1V05_NODE1_VIN_FLT")
		)
		(pad "2" smd rect
			(at -1.4732 0)
			(size 1.1684 1.5748)
			(layers "F.Cu" "F.Mask" "F.Paste")
			(net "GND")
		)
	)
	(footprint ""
		(layer "F.Cu")
		(at 122.79376 -185.205624 -90)
		(property "Reference" "R863"
			(at -4.768088 -0.152908 90)
			(unlocked yes)
			(layer "F.SilkS")
			(effects
				(font
					(size 0.7874 0.5842)
					(thickness 0.1524)
				)
				(justify left)
			)
		)
		(property "Value" ""
			(at 0 0 270)
			(layer "F.Fab")
			(effects
				(font
					(size 1.27 1.27)
				)
			)
		)
		(duplicate_pad_numbers_are_jumpers no)
		(fp_line
			(start -0.7874 0.4064)
			(end -0.7874 -0.4064)
			(stroke
				(width 0.1524)
				(type default)
			)
			(layer "F.SilkS")
		)
		(fp_line
			(start 0.7874 0.4064)
			(end -0.7874 0.4064)
			(stroke
				(width 0.1524)
				(type default)
			)
			(layer "F.SilkS")
		)
		(fp_line
			(start -0.7874 -0.4064)
			(end 0.7874 -0.4064)
			(stroke
				(width 0.1524)
				(type default)
			)
			(layer "F.SilkS")
		)
		(fp_line
			(start 0.7874 -0.4064)
			(end 0.7874 0.4064)
			(stroke
				(width 0.1524)
				(type default)
			)
			(layer "F.SilkS")
		)
		(fp_poly
			(pts
				(xy -0.508 0.2794) (xy -0.508 0.2286) (xy -0.635 0.2286) (xy -0.635 -0.254) (xy -0.5334 -0.254)
				(xy -0.5334 -0.2794) (xy 0.5334 -0.2794) (xy 0.5334 -0.254) (xy 0.635 -0.254) (xy 0.635 0.254) (xy 0.5334 0.254)
				(xy 0.5334 0.2794)
			)
			(stroke
				(width 0)
				(type default)
			)
			(fill no)
			(layer "F.CrtYd")
		)
		(pad "1" smd rect
			(at 0.40005 0 270)
			(size 0.4572 0.508)
			(layers "F.Cu" "F.Mask" "F.Paste")
			(net "T8_NODE2_EN")
		)
		(pad "2" smd rect
			(at -0.40005 0 270)
			(size 0.4572 0.508)
			(layers "F.Cu" "F.Mask" "F.Paste")
			(net "T8_NODE2_EN_R")
		)
	)
)
